FILE_TYPE = MACRO_DRAWING;
SET COLOR_WIRE YELLOW;
SET COLOR_PROP ORANGE;
SET COLOR_DOT WHITE;
SET COLOR_ARC YELLOW;
SET COLOR_BODY GREEN;
SET COLOR_NOTE PURPLE;
SET PROP_DISPLAY VALUE;
SET PAGE_NUMBER P244;
FORCEADD GND..1
(-7750 6525);
FORCEPROP 3 LASTPIN (-7750 6575) SIG_NAME GND\g
J 0
(-7740 6585);
DISPLAY 0.659574 (-7740 6585);
PAINT MONO (-7740 6585);
DISPLAY INVISIBLE (-7740 6585);
FORCEPROP 1 LAST HDL_POWER GND
J 0
(-7750 6675);
DISPLAY 0.872340 (-7750 6675);
PAINT GREEN (-7750 6675);
DISPLAY INVISIBLE (-7750 6675);
FORCEPROP 1 LAST SIZE 1B
J 0
(-7675 6475);
DISPLAY 0.872340 (-7675 6475);
PAINT AQUA (-7675 6475);
DISPLAY INVISIBLE (-7675 6475);
FORCEPROP 2 LAST CDS_LIB logical_power
J 0
(-7750 6525);
DISPLAY INVISIBLE (-7750 6525);
FORCEPROP 1 LAST PATH I1
J 0
(-7675 6525);
DISPLAY 0.872340 (-7675 6525);
PAINT AQUA (-7675 6525);
DISPLAY INVISIBLE (-7675 6525);
FORCEADD Q_RES..1
(-5550 5900);
FORCEPROP 1 LAST PART_NUMBER CS00002JB13
J 0
(-5525 5800);
DISPLAY 0.638298 (-5525 5800);
DISPLAY INVISIBLE (-5525 5800);
FORCEPROP 1 LAST TOLERANCE 5%
J 0
(-5425 5925);
DISPLAY 0.638298 (-5425 5925);
FORCEPROP 1 LAST VALUE 0
J 2
(-5525 5925);
DISPLAY 0.638298 (-5525 5925);
FORCEPROP 1 LAST MATERIAL CHIP
J 0
(-5750 5850);
DISPLAY 0.638298 (-5750 5850);
FORCEPROP 1 LAST WATTAGE 1/16W
J 2
(-5375 5850);
DISPLAY 0.638298 (-5375 5850);
FORCEPROP 1 LAST PACK_TYPE 0402LF
J 0
(-5750 5800);
DISPLAY 0.638298 (-5750 5800);
FORCEPROP 1 LAST LOCATION PR3337
J 0
(-5775 5925);
DISPLAY 0.638298 (-5775 5925);
FORCEPROP 1 LASTPIN (-5650 5900) $PN 1
J 0
(-5638 5912);
DISPLAY 0.787234 (-5638 5912);
PAINT MONO (-5638 5912);
FORCEPROP 1 LASTPIN (-5450 5900) $PN 2
J 0
(-5488 5912);
DISPLAY 0.787234 (-5488 5912);
PAINT MONO (-5488 5912);
FORCEPROP 2 LAST CDS_LIB pure_quanta
J 0
(-5550 5900);
DISPLAY INVISIBLE (-5550 5900);
FORCEPROP 1 LAST PATH I10
J 0
(-5600 6050);
DISPLAY 0.978723 (-5600 6050);
PAINT WHITE (-5600 6050);
DISPLAY INVISIBLE (-5600 6050);
FORCEPROP 0 LAST $SEC 1
J 0
(-5425 5975);
DISPLAY 0.680851 (-5425 5975);
PAINT MONO (-5425 5975);
DISPLAY INVISIBLE (-5425 5975);
FORCEPROP 0 LAST CDS_SEC 1
J 0
(-5425 5975);
DISPLAY 1.021277 (-5425 5975);
DISPLAY INVISIBLE (-5425 5975);
FORCEADD Q_CAP..1
(-6575 6750);
FORCEPROP 1 LAST PART_NUMBER CH6223MEA01
J 0
(-6525 6600);
DISPLAY 0.617021 (-6525 6600);
PAINT BLUE (-6525 6600);
DISPLAY INVISIBLE (-6525 6600);
FORCEPROP 1 LAST MATERIAL X6S
J 0
(-6525 6650);
DISPLAY 0.617021 (-6525 6650);
PAINT SKYBLUE (-6525 6650);
FORCEPROP 1 LAST PACK_TYPE C0805
J 0
(-6525 6550);
DISPLAY 0.617021 (-6525 6550);
PAINT SKYBLUE (-6525 6550);
FORCEPROP 1 LAST VOLTAGE 16V
J 0
(-6525 6750);
DISPLAY 0.617021 (-6525 6750);
PAINT SKYBLUE (-6525 6750);
FORCEPROP 1 LAST TOLERANCE 20%
J 0
(-6525 6700);
DISPLAY 0.617021 (-6525 6700);
PAINT SKYBLUE (-6525 6700);
FORCEPROP 1 LAST VALUE 22UF
J 0
(-6525 6800);
DISPLAY 0.617021 (-6525 6800);
PAINT SKYBLUE (-6525 6800);
FORCEPROP 1 LAST LOCATION PC1850
J 0
(-6525 6850);
DISPLAY 0.617021 (-6525 6850);
PAINT AQUA (-6525 6850);
FORCEPROP 1 LASTPIN (-6575 6850) $PN 1
J 0
(-6565 6830);
DISPLAY 0.617021 (-6565 6830);
PAINT MONO (-6565 6830);
FORCEPROP 1 LASTPIN (-6575 6650) $PN 2
J 0
(-6565 6630);
DISPLAY 0.617021 (-6565 6630);
PAINT MONO (-6565 6630);
FORCEPROP 2 LAST CDS_LIB pure_quanta
J 0
(-6575 6750);
DISPLAY INVISIBLE (-6575 6750);
FORCEPROP 1 LAST PATH I11
J 0
(-6525 6900);
DISPLAY 0.978723 (-6525 6900);
PAINT WHITE (-6525 6900);
DISPLAY INVISIBLE (-6525 6900);
FORCEPROP 0 LAST $SEC 1
J 0
(-6525 6900);
DISPLAY 0.680851 (-6525 6900);
PAINT MONO (-6525 6900);
DISPLAY INVISIBLE (-6525 6900);
FORCEPROP 0 LAST CDS_SEC 1
J 0
(-6525 6900);
DISPLAY 1.021277 (-6525 6900);
DISPLAY INVISIBLE (-6525 6900);
FORCEADD Q_CAP..1
(-6125 6750);
FORCEPROP 1 LAST PART_NUMBER CH6223MEA01
J 0
(-6075 6600);
DISPLAY 0.617021 (-6075 6600);
PAINT BLUE (-6075 6600);
DISPLAY INVISIBLE (-6075 6600);
FORCEPROP 1 LAST VALUE 22UF
J 0
(-6075 6800);
DISPLAY 0.617021 (-6075 6800);
PAINT SKYBLUE (-6075 6800);
FORCEPROP 1 LAST PACK_TYPE C0805
J 0
(-6075 6550);
DISPLAY 0.617021 (-6075 6550);
PAINT SKYBLUE (-6075 6550);
FORCEPROP 1 LAST VOLTAGE 16V
J 0
(-6075 6750);
DISPLAY 0.617021 (-6075 6750);
PAINT SKYBLUE (-6075 6750);
FORCEPROP 1 LAST TOLERANCE 20%
J 0
(-6075 6700);
DISPLAY 0.617021 (-6075 6700);
PAINT SKYBLUE (-6075 6700);
FORCEPROP 1 LAST MATERIAL X6S
J 0
(-6075 6650);
DISPLAY 0.617021 (-6075 6650);
PAINT SKYBLUE (-6075 6650);
FORCEPROP 1 LAST LOCATION PC1898
J 0
(-6075 6850);
DISPLAY 0.617021 (-6075 6850);
PAINT AQUA (-6075 6850);
FORCEPROP 1 LASTPIN (-6125 6850) $PN 1
J 0
(-6115 6830);
DISPLAY 0.617021 (-6115 6830);
PAINT MONO (-6115 6830);
FORCEPROP 1 LASTPIN (-6125 6650) $PN 2
J 0
(-6115 6630);
DISPLAY 0.617021 (-6115 6630);
PAINT MONO (-6115 6630);
FORCEPROP 2 LAST CDS_LIB pure_quanta
J 0
(-6125 6750);
DISPLAY INVISIBLE (-6125 6750);
FORCEPROP 1 LAST PATH I12
J 0
(-6075 6900);
DISPLAY 0.978723 (-6075 6900);
PAINT WHITE (-6075 6900);
DISPLAY INVISIBLE (-6075 6900);
FORCEPROP 0 LAST $SEC 1
J 0
(-6075 6900);
DISPLAY 0.680851 (-6075 6900);
PAINT MONO (-6075 6900);
DISPLAY INVISIBLE (-6075 6900);
FORCEPROP 0 LAST CDS_SEC 1
J 0
(-6075 6900);
DISPLAY 0.680851 (-6075 6900);
DISPLAY INVISIBLE (-6075 6900);
FORCEADD OFFPAGE..1
(-5775 6200);
PAINT AQUA (-5775 6200);
FORCEPROP 2 LAST $XR2 244 
J 0
(-6297 6200);
DISPLAY 0.638298 (-6297 6200);
PAINT MONO (-6297 6200);
FORCEPROP 2 LAST $XR1 222 
J 0
(-6177 6200);
DISPLAY 0.638298 (-6177 6200);
PAINT MONO (-6177 6200);
FORCEPROP 2 LAST $XR0 259 
J 0
(-6057 6200);
DISPLAY 0.638298 (-6057 6200);
PAINT MONO (-6057 6200);
FORCEPROP 1 LAST COMMENT_BODY TRUE
J 0
(-5650 6100);
DISPLAY 0.872340 (-5650 6100);
PAINT GREEN (-5650 6100);
DISPLAY INVISIBLE (-5650 6100);
FORCEPROP 1 LAST OFFPAGE TRUE
J 0
(-5450 6075);
DISPLAY 0.872340 (-5450 6075);
PAINT AQUA (-5450 6075);
DISPLAY INVISIBLE (-5450 6075);
FORCEPROP 2 LAST CDS_LIB standard
J 0
(-5775 6200);
DISPLAY INVISIBLE (-5775 6200);
FORCEPROP 2 LAST PATH I13
J 0
(-6050 6250);
DISPLAY 1.021277 (-6050 6250);
DISPLAY INVISIBLE (-6050 6250);
FORCEADD Q_CAP..1
(-5725 6750);
FORCEPROP 1 LAST PART_NUMBER CH5103KEB01
J 0
(-5675 6600);
DISPLAY 0.489362 (-5675 6600);
PAINT BLUE (-5675 6600);
DISPLAY INVISIBLE (-5675 6600);
FORCEPROP 1 LAST MATERIAL X6S
J 0
(-5675 6650);
DISPLAY 0.617021 (-5675 6650);
PAINT SKYBLUE (-5675 6650);
FORCEPROP 1 LAST TOLERANCE 10%
J 0
(-5675 6700);
DISPLAY 0.617021 (-5675 6700);
PAINT SKYBLUE (-5675 6700);
FORCEPROP 1 LAST PACK_TYPE C0402
J 0
(-5675 6550);
DISPLAY 0.617021 (-5675 6550);
PAINT SKYBLUE (-5675 6550);
FORCEPROP 1 LAST VOLTAGE 16V
J 0
(-5675 6750);
DISPLAY 0.617021 (-5675 6750);
PAINT SKYBLUE (-5675 6750);
FORCEPROP 1 LAST VALUE 1UF
J 0
(-5675 6800);
DISPLAY 0.617021 (-5675 6800);
PAINT SKYBLUE (-5675 6800);
FORCEPROP 1 LAST LOCATION PC1846
J 0
(-5675 6850);
DISPLAY 0.617021 (-5675 6850);
PAINT AQUA (-5675 6850);
FORCEPROP 1 LASTPIN (-5725 6850) $PN 1
J 0
(-5715 6830);
DISPLAY 0.787234 (-5715 6830);
PAINT MONO (-5715 6830);
FORCEPROP 1 LASTPIN (-5725 6650) $PN 2
J 0
(-5715 6630);
DISPLAY 0.787234 (-5715 6630);
PAINT MONO (-5715 6630);
FORCEPROP 2 LAST CDS_LIB pure_quanta
J 0
(-5725 6750);
DISPLAY INVISIBLE (-5725 6750);
FORCEPROP 1 LAST PATH I14
J 0
(-5675 6900);
DISPLAY 0.978723 (-5675 6900);
PAINT WHITE (-5675 6900);
DISPLAY INVISIBLE (-5675 6900);
FORCEPROP 0 LAST $SEC 1
J 0
(-5675 6900);
DISPLAY 0.680851 (-5675 6900);
PAINT MONO (-5675 6900);
DISPLAY INVISIBLE (-5675 6900);
FORCEPROP 0 LAST CDS_SEC 1
J 0
(-5675 6900);
DISPLAY 1.021277 (-5675 6900);
DISPLAY INVISIBLE (-5675 6900);
FORCEADD GND..1
(-5462 4893);
FORCEPROP 3 LASTPIN (-5462 4943) SIG_NAME GND\g
J 0
(-5452 4953);
DISPLAY 0.659574 (-5452 4953);
PAINT MONO (-5452 4953);
DISPLAY INVISIBLE (-5452 4953);
FORCEPROP 1 LAST HDL_POWER GND
J 0
(-5462 5043);
DISPLAY 0.872340 (-5462 5043);
PAINT GREEN (-5462 5043);
DISPLAY INVISIBLE (-5462 5043);
FORCEPROP 1 LAST SIZE 1B
J 0
(-5387 4843);
DISPLAY 0.872340 (-5387 4843);
PAINT AQUA (-5387 4843);
DISPLAY INVISIBLE (-5387 4843);
FORCEPROP 2 LAST CDS_LIB logical_power
J 0
(-5462 4893);
DISPLAY INVISIBLE (-5462 4893);
FORCEPROP 1 LAST PATH I15
J 0
(-5387 4893);
DISPLAY 0.872340 (-5387 4893);
PAINT AQUA (-5387 4893);
DISPLAY INVISIBLE (-5387 4893);
FORCEADD Q_RES..2
(-5462 5182);
FORCEPROP 1 LAST PART_NUMBER CS31692FB03
J 0
(-5422 5057);
DISPLAY 0.617021 (-5422 5057);
PAINT BLUE (-5422 5057);
DISPLAY INVISIBLE (-5422 5057);
FORCEPROP 1 LAST PACK_TYPE 0402LF
J 0
(-5422 5007);
DISPLAY 0.617021 (-5422 5007);
PAINT SKYBLUE (-5422 5007);
FORCEPROP 1 LAST WATTAGE 1/16W
J 0
(-5422 5157);
DISPLAY 0.617021 (-5422 5157);
PAINT SKYBLUE (-5422 5157);
FORCEPROP 1 LAST MATERIAL CHIP
J 0
(-5422 5107);
DISPLAY 0.617021 (-5422 5107);
PAINT SKYBLUE (-5422 5107);
FORCEPROP 1 LAST VALUE 16.9K
J 0
(-5417 5257);
DISPLAY 0.617021 (-5417 5257);
PAINT SKYBLUE (-5417 5257);
FORCEPROP 1 LAST TOLERANCE 1%
J 0
(-5417 5207);
DISPLAY 0.617021 (-5417 5207);
PAINT SKYBLUE (-5417 5207);
FORCEPROP 1 LAST LOCATION PR89
J 0
(-5417 5307);
DISPLAY 0.617021 (-5417 5307);
PAINT AQUA (-5417 5307);
FORCEPROP 1 LASTPIN (-5462 5282) $PN 1
J 0
(-5457 5244);
DISPLAY 0.617021 (-5457 5244);
FORCEPROP 1 LASTPIN (-5462 5082) $PN 2
J 0
(-5457 5092);
DISPLAY 0.617021 (-5457 5092);
FORCEPROP 2 LAST SEC_TYPE 0402LF
J 0
(-5400 5425);
DISPLAY 1.021277 (-5400 5425);
DISPLAY INVISIBLE (-5400 5425);
FORCEPROP 2 LAST CDS_LIB pure_quanta
R 3
J 0
(-5462 5182);
DISPLAY INVISIBLE (-5462 5182);
FORCEPROP 1 LAST PATH I16
J 0
(-5412 5357);
DISPLAY 0.978723 (-5412 5357);
PAINT WHITE (-5412 5357);
DISPLAY INVISIBLE (-5412 5357);
FORCEPROP 2 LAST SEC 1
J 0
(-5400 5425);
DISPLAY 0.680851 (-5400 5425);
PAINT MONO (-5400 5425);
DISPLAY INVISIBLE (-5400 5425);
FORCEADD GND..1
(-3950 5075);
FORCEPROP 3 LASTPIN (-3950 5125) SIG_NAME GND\g
J 0
(-3940 5135);
DISPLAY 0.659574 (-3940 5135);
PAINT MONO (-3940 5135);
DISPLAY INVISIBLE (-3940 5135);
FORCEPROP 1 LAST HDL_POWER GND
J 0
(-3950 5225);
DISPLAY 0.872340 (-3950 5225);
PAINT GREEN (-3950 5225);
DISPLAY INVISIBLE (-3950 5225);
FORCEPROP 1 LAST SIZE 1B
J 0
(-3875 5025);
DISPLAY 0.872340 (-3875 5025);
PAINT AQUA (-3875 5025);
DISPLAY INVISIBLE (-3875 5025);
FORCEPROP 2 LAST CDS_LIB logical_power
J 0
(-3950 5075);
DISPLAY INVISIBLE (-3950 5075);
FORCEPROP 1 LAST PATH I17
J 0
(-3875 5075);
DISPLAY 0.872340 (-3875 5075);
PAINT AQUA (-3875 5075);
DISPLAY INVISIBLE (-3875 5075);
FORCEADD GND..1
(-3825 5075);
FORCEPROP 3 LASTPIN (-3825 5125) SIG_NAME GND\g
J 0
(-3815 5135);
DISPLAY 0.659574 (-3815 5135);
PAINT MONO (-3815 5135);
DISPLAY INVISIBLE (-3815 5135);
FORCEPROP 1 LAST HDL_POWER GND
J 0
(-3825 5225);
DISPLAY 0.872340 (-3825 5225);
PAINT GREEN (-3825 5225);
DISPLAY INVISIBLE (-3825 5225);
FORCEPROP 1 LAST SIZE 1B
J 0
(-3750 5025);
DISPLAY 0.872340 (-3750 5025);
PAINT AQUA (-3750 5025);
DISPLAY INVISIBLE (-3750 5025);
FORCEPROP 2 LAST CDS_LIB logical_power
J 0
(-3825 5075);
DISPLAY INVISIBLE (-3825 5075);
FORCEPROP 1 LAST PATH I18
J 0
(-3750 5075);
DISPLAY 0.872340 (-3750 5075);
PAINT AQUA (-3750 5075);
DISPLAY INVISIBLE (-3750 5075);
FORCEADD GND..1
(-5150 5825);
FORCEPROP 3 LASTPIN (-5150 5875) SIG_NAME GND\g
J 0
(-5140 5885);
DISPLAY 0.659574 (-5140 5885);
PAINT MONO (-5140 5885);
DISPLAY INVISIBLE (-5140 5885);
FORCEPROP 1 LAST HDL_POWER GND
J 0
(-5150 5975);
DISPLAY 0.872340 (-5150 5975);
PAINT GREEN (-5150 5975);
DISPLAY INVISIBLE (-5150 5975);
FORCEPROP 2 LAST CDS_LIB logical_power
J 0
(-5150 5825);
DISPLAY INVISIBLE (-5150 5825);
FORCEPROP 1 LAST SIZE 1B
J 0
(-5075 5775);
DISPLAY 0.872340 (-5075 5775);
PAINT AQUA (-5075 5775);
DISPLAY INVISIBLE (-5075 5775);
FORCEPROP 1 LAST PATH I19
J 0
(-5075 5825);
DISPLAY 0.872340 (-5075 5825);
PAINT AQUA (-5075 5825);
DISPLAY INVISIBLE (-5075 5825);
FORCEADD Q_CAP..1
(-7750 6775);
FORCEPROP 1 LAST PART_NUMBER CH4106K1B01
J 0
(-7700 6625);
DISPLAY 0.787234 (-7700 6625);
DISPLAY INVISIBLE (-7700 6625);
FORCEPROP 1 LAST MATERIAL X7R
J 0
(-7700 6675);
DISPLAY 0.787234 (-7700 6675);
FORCEPROP 1 LAST TOLERANCE 10%
J 0
(-7700 6725);
DISPLAY 0.787234 (-7700 6725);
FORCEPROP 1 LAST VOLTAGE 50V
J 0
(-7700 6775);
DISPLAY 0.787234 (-7700 6775);
FORCEPROP 1 LAST PACK_TYPE C0402
J 0
(-7700 6575);
DISPLAY 0.787234 (-7700 6575);
FORCEPROP 1 LAST VALUE 100NF
J 0
(-7700 6825);
DISPLAY 0.787234 (-7700 6825);
FORCEPROP 1 LAST LOCATION PC1648
J 0
(-7700 6875);
DISPLAY 0.787234 (-7700 6875);
FORCEPROP 1 LASTPIN (-7750 6875) $PN 1
J 0
(-7740 6855);
DISPLAY 0.787234 (-7740 6855);
PAINT MONO (-7740 6855);
FORCEPROP 1 LASTPIN (-7750 6675) $PN 2
J 0
(-7740 6655);
DISPLAY 0.787234 (-7740 6655);
PAINT MONO (-7740 6655);
FORCEPROP 2 LAST CDS_LIB pure_quanta
J 0
(-7750 6775);
DISPLAY INVISIBLE (-7750 6775);
FORCEPROP 1 LAST PATH I2
J 0
(-7700 6925);
DISPLAY 0.978723 (-7700 6925);
PAINT WHITE (-7700 6925);
DISPLAY INVISIBLE (-7700 6925);
FORCEPROP 0 LAST $SEC 1
J 0
(-7700 6925);
DISPLAY 0.680851 (-7700 6925);
PAINT MONO (-7700 6925);
DISPLAY INVISIBLE (-7700 6925);
FORCEPROP 0 LAST CDS_SEC 1
J 0
(-7700 6925);
DISPLAY 1.021277 (-7700 6925);
DISPLAY INVISIBLE (-7700 6925);
FORCEADD RS53318LR..1
(-4575 6025);
FORCEPROP 1 LAST PART_NUMBER AL053318002
J 0
(-4820 6909);
DISPLAY 0.723404 (-4820 6909);
PAINT GREEN (-4820 6909);
DISPLAY INVISIBLE (-4820 6909);
FORCEPROP 1 LAST MATERIAL IC
J 0
(-4820 6782);
DISPLAY 0.723404 (-4820 6782);
PAINT GREEN (-4820 6782);
FORCEPROP 2 LAST VALUE RS53318LR
J 0
(-4825 7000);
DISPLAY 0.617021 (-4825 7000);
PAINT SKYBLUE (-4825 7000);
FORCEPROP 2 LAST PART_TYPE SMLF
J 0
(-4825 7050);
DISPLAY 0.680851 (-4825 7050);
FORCEPROP 1 LAST LOCATION PU181
J 0
(-4825 7125);
DISPLAY 0.723404 (-4825 7125);
PAINT GREEN (-4825 7125);
FORCEPROP 2 LASTPIN (-4175 5350) $PN 2
J 0
(-4165 5360);
DISPLAY 0.680851 (-4165 5360);
PAINT MONO (-4165 5360);
FORCEPROP 2 LASTPIN (-4175 6500) $PN 1
J 0
(-4165 6510);
DISPLAY 0.680851 (-4165 6510);
PAINT MONO (-4165 6510);
FORCEPROP 2 LASTPIN (-4975 5400) $PN 3
J 2
(-4985 5410);
DISPLAY 0.680851 (-4985 5410);
PAINT MONO (-4985 5410);
FORCEPROP 2 LASTPIN (-4975 6200) $PN 8
J 2
(-4985 6210);
DISPLAY 0.680851 (-4985 6210);
PAINT MONO (-4985 6210);
FORCEPROP 2 LASTPIN (-4175 5750) $PN 7
J 0
(-4165 5760);
DISPLAY 0.680851 (-4165 5760);
PAINT MONO (-4165 5760);
FORCEPROP 2 LASTPIN (-4975 6000) $PN 4
J 2
(-4985 6010);
DISPLAY 0.680851 (-4985 6010);
PAINT MONO (-4985 6010);
FORCEPROP 2 LASTPIN (-4175 5400) $PN 11_18
J 0
(-4165 5410);
DISPLAY 0.680851 (-4165 5410);
PAINT MONO (-4165 5410);
FORCEPROP 2 LASTPIN (-4175 6700) $PN 9
J 0
(-4165 6710);
DISPLAY 0.680851 (-4165 6710);
PAINT MONO (-4165 6710);
FORCEPROP 2 LASTPIN (-4175 5500) $PN 5
J 0
(-4165 5510);
DISPLAY 0.680851 (-4165 5510);
PAINT MONO (-4165 5510);
FORCEPROP 2 LASTPIN (-4175 5600) $PN 6
J 0
(-4165 5610);
DISPLAY 0.680851 (-4165 5610);
PAINT MONO (-4165 5610);
FORCEPROP 2 LASTPIN (-4175 6200) $PN 20
J 0
(-4165 6210);
DISPLAY 0.680851 (-4165 6210);
PAINT MONO (-4165 6210);
FORCEPROP 2 LASTPIN (-4975 5750) $PN 19
J 2
(-4985 5760);
DISPLAY 0.680851 (-4985 5760);
PAINT MONO (-4985 5760);
FORCEPROP 2 LASTPIN (-4975 6700) $PN 10
J 2
(-4985 6710);
DISPLAY 0.680851 (-4985 6710);
PAINT MONO (-4985 6710);
FORCEPROP 2 LASTPIN (-4975 6650) $PN 21
J 2
(-4985 6660);
DISPLAY 0.680851 (-4985 6660);
PAINT MONO (-4985 6660);
FORCEPROP 2 LAST SEC_TYPE 
J 0
(-4825 7100);
DISPLAY 1.021277 (-4825 7100);
DISPLAY INVISIBLE (-4825 7100);
FORCEPROP 2 LAST CDS_LIB pure_quanta
J 0
(-4575 6025);
DISPLAY INVISIBLE (-4575 6025);
FORCEPROP 1 LAST NEEDS_NO_SIZE TRUE
J 0
(-4575 6025);
DISPLAY 0.723404 (-4575 6025);
PAINT GREEN (-4575 6025);
DISPLAY INVISIBLE (-4575 6025);
FORCEPROP 1 LAST CDS_LMAN_SYM_OUTLINE -250,725,250,-725
J 0
(-4575 6025);
DISPLAY 0.468085 (-4575 6025);
PAINT GREEN (-4575 6025);
DISPLAY INVISIBLE (-4575 6025);
FORCEPROP 1 LAST PATH I20
J 0
(-4575 6025);
DISPLAY 0.723404 (-4575 6025);
PAINT GREEN (-4575 6025);
DISPLAY INVISIBLE (-4575 6025);
FORCEPROP 2 LAST SEC 1
J 0
(-4825 7100);
DISPLAY 0.680851 (-4825 7100);
PAINT MONO (-4825 7100);
DISPLAY INVISIBLE (-4825 7100);
FORCEADD Q_CAP..1
(-3825 5300);
FORCEPROP 1 LAST PART_NUMBER CH4104K1B00
J 0
(-3775 5175);
DISPLAY 0.617021 (-3775 5175);
PAINT BLUE (-3775 5175);
DISPLAY INVISIBLE (-3775 5175);
FORCEPROP 1 LAST TOLERANCE 10%
J 0
(-3775 5275);
DISPLAY 0.617021 (-3775 5275);
PAINT SKYBLUE (-3775 5275);
FORCEPROP 1 LAST VOLTAGE 25V
J 0
(-3775 5325);
DISPLAY 0.617021 (-3775 5325);
PAINT SKYBLUE (-3775 5325);
FORCEPROP 1 LAST VALUE 0.1UF
J 0
(-3775 5375);
DISPLAY 0.617021 (-3775 5375);
PAINT SKYBLUE (-3775 5375);
FORCEPROP 1 LAST MATERIAL X7R
J 0
(-3775 5225);
DISPLAY 0.617021 (-3775 5225);
PAINT SKYBLUE (-3775 5225);
FORCEPROP 1 LAST PACK_TYPE 0402
J 0
(-3775 5125);
DISPLAY 0.617021 (-3775 5125);
PAINT SKYBLUE (-3775 5125);
FORCEPROP 1 LAST LOCATION PC1853
J 0
(-3775 5425);
DISPLAY 0.617021 (-3775 5425);
PAINT AQUA (-3775 5425);
FORCEPROP 1 LASTPIN (-3825 5400) $PN 1
J 0
(-3815 5380);
DISPLAY 0.617021 (-3815 5380);
FORCEPROP 1 LASTPIN (-3825 5200) $PN 2
J 0
(-3815 5180);
DISPLAY 0.617021 (-3815 5180);
FORCEPROP 2 LAST CDS_LIB pure_quanta
J 0
(-3825 5300);
DISPLAY INVISIBLE (-3825 5300);
FORCEPROP 1 LAST PATH I21
J 0
(-3775 5450);
DISPLAY 0.978723 (-3775 5450);
PAINT WHITE (-3775 5450);
DISPLAY INVISIBLE (-3775 5450);
FORCEPROP 2 LAST $SEC 1
J 0
(-3775 5500);
DISPLAY 0.680851 (-3775 5500);
PAINT MONO (-3775 5500);
DISPLAY INVISIBLE (-3775 5500);
FORCEPROP 2 LAST CDS_SEC 1
J 0
(-3775 5500);
DISPLAY 0.680851 (-3775 5500);
DISPLAY INVISIBLE (-3775 5500);
FORCEADD Q_CAP..2
(-1900 5075);
FORCEPROP 1 LAST PART_NUMBER TMP_QCH04706JB01
J 1
(-1900 5125);
DISPLAY 0.617021 (-1900 5125);
PAINT BLUE (-1900 5125);
DISPLAY INVISIBLE (-1900 5125);
FORCEPROP 1 LAST PACK_TYPE 0402
J 1
(-1900 4875);
DISPLAY 0.617021 (-1900 4875);
PAINT SKYBLUE (-1900 4875);
FORCEPROP 1 LAST MATERIAL NPO
J 0
(-1900 4925);
DISPLAY 0.617021 (-1900 4925);
PAINT SKYBLUE (-1900 4925);
FORCEPROP 1 LAST TOLERANCE 5%
J 2
(-1900 4925);
DISPLAY 0.617021 (-1900 4925);
PAINT SKYBLUE (-1900 4925);
FORCEPROP 1 LAST VOLTAGE 50V
J 0
(-1900 4975);
DISPLAY 0.617021 (-1900 4975);
PAINT SKYBLUE (-1900 4975);
FORCEPROP 1 LAST VALUE 47PF
J 2
(-1900 4975);
DISPLAY 0.617021 (-1900 4975);
PAINT SKYBLUE (-1900 4975);
FORCEPROP 1 LAST LOCATION PC1877
J 1
(-1900 5175);
DISPLAY 0.617021 (-1900 5175);
PAINT AQUA (-1900 5175);
FORCEPROP 1 LASTPIN (-2000 5075) $PN 1
J 0
(-2010 5090);
DISPLAY 0.617021 (-2010 5090);
PAINT MONO (-2010 5090);
FORCEPROP 1 LASTPIN (-1800 5075) $PN 2
J 0
(-1815 5090);
DISPLAY 0.617021 (-1815 5090);
PAINT MONO (-1815 5090);
FORCEPROP 2 LAST CDS_LIB pure_quanta
J 0
(-1900 5075);
DISPLAY INVISIBLE (-1900 5075);
FORCEPROP 1 LAST PATH I22
J 0
(-1900 5275);
DISPLAY 0.978723 (-1900 5275);
PAINT WHITE (-1900 5275);
DISPLAY INVISIBLE (-1900 5275);
FORCEPROP 0 LAST $SEC 1
J 0
(-1900 5225);
DISPLAY 0.680851 (-1900 5225);
PAINT MONO (-1900 5225);
DISPLAY INVISIBLE (-1900 5225);
FORCEPROP 0 LAST CDS_SEC 1
J 0
(-1900 5225);
DISPLAY 0.680851 (-1900 5225);
DISPLAY INVISIBLE (-1900 5225);
FORCEADD GND..1
(-3400 5150);
FORCEPROP 3 LASTPIN (-3400 5200) SIG_NAME GND\g
J 0
(-3390 5210);
DISPLAY 0.659574 (-3390 5210);
PAINT MONO (-3390 5210);
DISPLAY INVISIBLE (-3390 5210);
FORCEPROP 1 LAST HDL_POWER GND
J 0
(-3400 5300);
DISPLAY 0.872340 (-3400 5300);
PAINT GREEN (-3400 5300);
DISPLAY INVISIBLE (-3400 5300);
FORCEPROP 1 LAST SIZE 1B
J 0
(-3325 5100);
DISPLAY 0.872340 (-3325 5100);
PAINT AQUA (-3325 5100);
DISPLAY INVISIBLE (-3325 5100);
FORCEPROP 2 LAST CDS_LIB logical_power
J 0
(-3400 5150);
DISPLAY INVISIBLE (-3400 5150);
FORCEPROP 1 LAST PATH I23
J 0
(-3325 5150);
DISPLAY 0.872340 (-3325 5150);
PAINT AQUA (-3325 5150);
DISPLAY INVISIBLE (-3325 5150);
FORCEADD GND..1
(-3250 5150);
FORCEPROP 3 LASTPIN (-3250 5200) SIG_NAME GND\g
J 0
(-3240 5210);
DISPLAY 0.659574 (-3240 5210);
PAINT MONO (-3240 5210);
DISPLAY INVISIBLE (-3240 5210);
FORCEPROP 1 LAST HDL_POWER GND
J 0
(-3250 5300);
DISPLAY 0.872340 (-3250 5300);
PAINT GREEN (-3250 5300);
DISPLAY INVISIBLE (-3250 5300);
FORCEPROP 1 LAST SIZE 1B
J 0
(-3175 5100);
DISPLAY 0.872340 (-3175 5100);
PAINT AQUA (-3175 5100);
DISPLAY INVISIBLE (-3175 5100);
FORCEPROP 2 LAST CDS_LIB logical_power
J 0
(-3250 5150);
DISPLAY INVISIBLE (-3250 5150);
FORCEPROP 1 LAST PATH I24
J 0
(-3175 5150);
DISPLAY 0.872340 (-3175 5150);
PAINT AQUA (-3175 5150);
DISPLAY INVISIBLE (-3175 5150);
FORCEADD Q_RES..2
(-3250 5475);
FORCEPROP 1 LAST PART_NUMBER CS31182BB06
J 0
(-3210 5350);
DISPLAY 0.617021 (-3210 5350);
PAINT BLUE (-3210 5350);
DISPLAY INVISIBLE (-3210 5350);
FORCEPROP 1 LAST MATERIAL CHIP
J 0
(-3210 5400);
DISPLAY 0.617021 (-3210 5400);
PAINT SKYBLUE (-3210 5400);
FORCEPROP 1 LAST PACK_TYPE 0402LF
J 0
(-3210 5300);
DISPLAY 0.617021 (-3210 5300);
PAINT SKYBLUE (-3210 5300);
FORCEPROP 1 LAST VALUE 11.8K
J 0
(-3205 5550);
DISPLAY 0.617021 (-3205 5550);
PAINT SKYBLUE (-3205 5550);
FORCEPROP 1 LAST WATTAGE 1/16W
J 0
(-3210 5450);
DISPLAY 0.617021 (-3210 5450);
PAINT SKYBLUE (-3210 5450);
FORCEPROP 1 LAST TOLERANCE 0.1%
J 0
(-3205 5500);
DISPLAY 0.617021 (-3205 5500);
PAINT SKYBLUE (-3205 5500);
FORCEPROP 1 LAST LOCATION PR91
J 0
(-3205 5600);
DISPLAY 0.617021 (-3205 5600);
PAINT AQUA (-3205 5600);
FORCEPROP 1 LASTPIN (-3250 5575) $PN 1
J 0
(-3245 5537);
DISPLAY 0.617021 (-3245 5537);
FORCEPROP 1 LASTPIN (-3250 5375) $PN 2
J 0
(-3245 5385);
DISPLAY 0.617021 (-3245 5385);
FORCEPROP 2 LAST CDS_LIB pure_quanta
J 0
(-3250 5475);
DISPLAY INVISIBLE (-3250 5475);
FORCEPROP 1 LAST PATH I25
J 0
(-3200 5650);
DISPLAY 0.978723 (-3200 5650);
PAINT WHITE (-3200 5650);
DISPLAY INVISIBLE (-3200 5650);
FORCEPROP 2 LAST $SEC 1
J 0
(-3200 5700);
DISPLAY 0.680851 (-3200 5700);
PAINT MONO (-3200 5700);
DISPLAY INVISIBLE (-3200 5700);
FORCEPROP 2 LAST CDS_SEC 1
J 0
(-3200 5700);
DISPLAY 0.680851 (-3200 5700);
DISPLAY INVISIBLE (-3200 5700);
FORCEADD Q_CAP..1
(-3300 6350);
FORCEPROP 1 LAST PART_NUMBER CH4224K1B01
J 0
(-3250 6275);
DISPLAY 0.617021 (-3250 6275);
PAINT BLUE (-3250 6275);
DISPLAY INVISIBLE (-3250 6275);
FORCEPROP 1 LAST VALUE 0.22UF
J 0
(-3250 6475);
DISPLAY 0.617021 (-3250 6475);
PAINT SKYBLUE (-3250 6475);
FORCEPROP 1 LAST MATERIAL X7R
J 0
(-3250 6325);
DISPLAY 0.617021 (-3250 6325);
PAINT SKYBLUE (-3250 6325);
FORCEPROP 1 LAST PACK_TYPE C0402
J 0
(-3250 6225);
DISPLAY 0.617021 (-3250 6225);
PAINT SKYBLUE (-3250 6225);
FORCEPROP 1 LAST VOLTAGE 25V
J 0
(-3250 6425);
DISPLAY 0.617021 (-3250 6425);
PAINT SKYBLUE (-3250 6425);
FORCEPROP 1 LAST TOLERANCE 10%
J 0
(-3250 6375);
DISPLAY 0.617021 (-3250 6375);
PAINT SKYBLUE (-3250 6375);
FORCEPROP 1 LAST LOCATION PC1847
J 0
(-3250 6525);
DISPLAY 0.617021 (-3250 6525);
PAINT AQUA (-3250 6525);
FORCEPROP 1 LASTPIN (-3300 6450) $PN 1
J 0
(-3290 6430);
DISPLAY 0.787234 (-3290 6430);
PAINT MONO (-3290 6430);
FORCEPROP 1 LASTPIN (-3300 6250) $PN 2
J 0
(-3290 6230);
DISPLAY 0.787234 (-3290 6230);
PAINT MONO (-3290 6230);
FORCEPROP 2 LAST CDS_LIB pure_quanta
J 0
(-3300 6350);
DISPLAY INVISIBLE (-3300 6350);
FORCEPROP 1 LAST PATH I26
J 0
(-3250 6500);
DISPLAY 0.978723 (-3250 6500);
PAINT WHITE (-3250 6500);
DISPLAY INVISIBLE (-3250 6500);
FORCEPROP 0 LAST $SEC 1
J 0
(-3250 6575);
DISPLAY 0.680851 (-3250 6575);
PAINT MONO (-3250 6575);
DISPLAY INVISIBLE (-3250 6575);
FORCEPROP 0 LAST CDS_SEC 1
J 0
(-3250 6575);
DISPLAY 1.021277 (-3250 6575);
DISPLAY INVISIBLE (-3250 6575);
FORCEADD Q_RES..2
(-3300 7075);
FORCEPROP 1 LAST PART_NUMBER CS31002FB08
J 0
(-3260 6950);
DISPLAY 0.617021 (-3260 6950);
PAINT BLUE (-3260 6950);
DISPLAY INVISIBLE (-3260 6950);
FORCEPROP 1 LAST MATERIAL CHIP
J 0
(-3260 7000);
DISPLAY 0.617021 (-3260 7000);
PAINT SKYBLUE (-3260 7000);
FORCEPROP 1 LAST TOLERANCE 1%
J 0
(-3255 7100);
DISPLAY 0.617021 (-3255 7100);
PAINT SKYBLUE (-3255 7100);
FORCEPROP 1 LAST WATTAGE 1/16W
J 0
(-3260 7050);
DISPLAY 0.617021 (-3260 7050);
PAINT SKYBLUE (-3260 7050);
FORCEPROP 1 LAST VALUE 10K
J 0
(-3255 7150);
DISPLAY 0.617021 (-3255 7150);
PAINT SKYBLUE (-3255 7150);
FORCEPROP 1 LAST PACK_TYPE 0402LF
J 0
(-3260 6900);
DISPLAY 0.617021 (-3260 6900);
PAINT SKYBLUE (-3260 6900);
FORCEPROP 1 LAST LOCATION R2356
J 0
(-3255 7200);
DISPLAY 0.617021 (-3255 7200);
PAINT AQUA (-3255 7200);
FORCEPROP 1 LASTPIN (-3300 7175) $PN 1
J 0
(-3295 7137);
DISPLAY 0.617021 (-3295 7137);
FORCEPROP 1 LASTPIN (-3300 6975) $PN 2
J 0
(-3295 6985);
DISPLAY 0.617021 (-3295 6985);
FORCEPROP 2 LAST CDS_LIB pure_quanta
R 3
J 0
(-3300 7075);
PAINT MONO (-3300 7075);
DISPLAY INVISIBLE (-3300 7075);
FORCEPROP 2 LAST SEC_TYPE 0402LF
J 0
(-3249 7304);
DISPLAY 1.021277 (-3249 7304);
DISPLAY INVISIBLE (-3249 7304);
FORCEPROP 1 LAST PATH I27
J 0
(-3250 7250);
DISPLAY 0.978723 (-3250 7250);
PAINT WHITE (-3250 7250);
DISPLAY INVISIBLE (-3250 7250);
FORCEPROP 2 LAST SEC 1
J 0
(-3249 7304);
DISPLAY 0.680851 (-3249 7304);
PAINT MONO (-3249 7304);
DISPLAY INVISIBLE (-3249 7304);
FORCEADD Q_RES..1
(-2725 6700);
FORCEPROP 1 LAST PART_NUMBER CS00002JB13
J 0
(-2850 6750);
DISPLAY 0.617021 (-2850 6750);
PAINT BLUE (-2850 6750);
DISPLAY INVISIBLE (-2850 6750);
FORCEPROP 1 LAST VALUE 0
J 2
(-2575 6700);
DISPLAY 0.617021 (-2575 6700);
PAINT SKYBLUE (-2575 6700);
FORCEPROP 1 LAST WATTAGE 1/16W
J 2
(-2550 6800);
DISPLAY 0.617021 (-2550 6800);
PAINT SKYBLUE (-2550 6800);
FORCEPROP 1 LAST MATERIAL CHIP
J 0
(-2850 6800);
DISPLAY 0.617021 (-2850 6800);
PAINT SKYBLUE (-2850 6800);
FORCEPROP 1 LAST TOLERANCE 5%
J 0
(-2550 6700);
DISPLAY 0.617021 (-2550 6700);
PAINT SKYBLUE (-2550 6700);
FORCEPROP 1 LAST PACK_TYPE 0402LF
J 0
(-2850 6850);
DISPLAY 0.617021 (-2850 6850);
PAINT SKYBLUE (-2850 6850);
FORCEPROP 1 LAST LOCATION R2316
J 0
(-2950 6700);
DISPLAY 0.638298 (-2950 6700);
FORCEPROP 1 LASTPIN (-2825 6700) $PN 1
J 0
(-2813 6712);
DISPLAY 0.787234 (-2813 6712);
PAINT MONO (-2813 6712);
FORCEPROP 1 LASTPIN (-2625 6700) $PN 2
J 0
(-2663 6712);
DISPLAY 0.787234 (-2663 6712);
PAINT MONO (-2663 6712);
FORCEPROP 2 LAST CDS_LIB pure_quanta
J 0
(-2725 6700);
DISPLAY INVISIBLE (-2725 6700);
FORCEPROP 1 LAST PATH I28
J 0
(-2775 6850);
DISPLAY 0.978723 (-2775 6850);
PAINT WHITE (-2775 6850);
DISPLAY INVISIBLE (-2775 6850);
FORCEPROP 0 LAST $SEC 1
J 0
(-2850 6900);
DISPLAY 0.680851 (-2850 6900);
PAINT MONO (-2850 6900);
DISPLAY INVISIBLE (-2850 6900);
FORCEPROP 0 LAST CDS_SEC 1
J 0
(-2850 6900);
DISPLAY 1.021277 (-2850 6900);
DISPLAY INVISIBLE (-2850 6900);
FORCEADD P1V0_AUX..1
(-7746 7195);
FORCEPROP 3 LASTPIN (-7746 7145) SIG_NAME P12V_AUX\g
J 0
(-7736 7155);
DISPLAY 0.659574 (-7736 7155);
PAINT MONO (-7736 7155);
DISPLAY INVISIBLE (-7736 7155);
FORCEPROP 1 LAST HDL_POWER P12V_AUX
J 1
(-7735 7242);
DISPLAY 0.617021 (-7735 7242);
PAINT GREEN (-7735 7242);
FORCEPROP 2 LAST ROOM VR_DDR1_POWER_STAGE
J 0
(-7746 7295);
DISPLAY 0.978723 (-7746 7295);
DISPLAY INVISIBLE (-7746 7295);
FORCEPROP 2 LAST CDS_LIB logical_power
J 0
(-7746 7195);
DISPLAY INVISIBLE (-7746 7195);
FORCEPROP 1 LAST PATH I3
J 0
(-7696 7220);
DISPLAY 0.872340 (-7696 7220);
PAINT AQUA (-7696 7220);
DISPLAY INVISIBLE (-7696 7220);
FORCEADD Q_INDUCTOR..1
(-2400 6225);
FORCEPROP 1 LAST PART_NUMBER CV-47A0MZ10
J 0
(-2525 6335);
DISPLAY 0.617021 (-2525 6335);
PAINT BLUE (-2525 6335);
DISPLAY INVISIBLE (-2525 6335);
FORCEPROP 1 LAST MATERIAL IND
J 0
(-2525 6280);
DISPLAY 0.617021 (-2525 6280);
PAINT SKYBLUE (-2525 6280);
FORCEPROP 2 LAST VALUE 4.7UH
J 0
(-2525 6425);
DISPLAY 0.617021 (-2525 6425);
PAINT SKYBLUE (-2525 6425);
FORCEPROP 2 LAST PACK_TYPE SMLF
J 0
(-2525 6475);
DISPLAY 0.617021 (-2525 6475);
PAINT SKYBLUE (-2525 6475);
FORCEPROP 1 LAST LOCATION PL65
J 0
(-2525 6385);
DISPLAY 0.617021 (-2525 6385);
PAINT AQUA (-2525 6385);
FORCEPROP 2 LASTPIN (-2500 6200) $PN 1
J 2
(-2510 6210);
DISPLAY 0.617021 (-2510 6210);
FORCEPROP 2 LASTPIN (-2300 6200) $PN 2
J 0
(-2290 6210);
DISPLAY 0.617021 (-2290 6210);
FORCEPROP 2 LAST CDS_LIB pure_quanta
J 0
(-2400 6225);
DISPLAY INVISIBLE (-2400 6225);
FORCEPROP 1 LAST NEEDS_NO_SIZE TRUE
J 0
(-2400 6225);
DISPLAY 0.468085 (-2400 6225);
PAINT GREEN (-2400 6225);
DISPLAY INVISIBLE (-2400 6225);
FORCEPROP 1 LAST PATH I30
J 0
(-2325 6280);
DISPLAY 0.723404 (-2325 6280);
PAINT GREEN (-2325 6280);
DISPLAY INVISIBLE (-2325 6280);
FORCEPROP 2 LAST $SEC 1
J 0
(-2525 6525);
DISPLAY 0.680851 (-2525 6525);
PAINT MONO (-2525 6525);
DISPLAY INVISIBLE (-2525 6525);
FORCEPROP 2 LAST CDS_SEC 1
J 0
(-2525 6525);
DISPLAY 0.680851 (-2525 6525);
DISPLAY INVISIBLE (-2525 6525);
FORCEADD OFFPAGE..2
(-1650 6700);
FORCEPROP 2 LAST $XR0 213 
J 0
(-1461 6700);
DISPLAY 0.638298 (-1461 6700);
PAINT MONO (-1461 6700);
FORCEPROP 1 LAST COMMENT_BODY TRUE
J 0
(-1695 6605);
DISPLAY 0.531915 (-1695 6605);
PAINT GREEN (-1695 6605);
DISPLAY INVISIBLE (-1695 6605);
FORCEPROP 1 LAST OFFPAGE TRUE
J 0
(-1325 6575);
DISPLAY 0.531915 (-1325 6575);
PAINT GREEN (-1325 6575);
DISPLAY INVISIBLE (-1325 6575);
FORCEPROP 2 LAST BOM_COST VR_SYSTEM 
J 0
(-1300 6750);
DISPLAY 0.680851 (-1300 6750);
DISPLAY INVISIBLE (-1300 6750);
FORCEPROP 2 LAST CDS_LIB standard
J 0
(-1650 6700);
PAINT MONO (-1650 6700);
DISPLAY INVISIBLE (-1650 6700);
FORCEPROP 2 LAST PATH I31
J 0
(-1450 6750);
DISPLAY 1.021277 (-1450 6750);
DISPLAY INVISIBLE (-1450 6750);
FORCEADD Q_CAPP..1
(-1125 5950);
FORCEPROP 1 LAST PART_NUMBER CC72201MZ28
J 0
(-1075 5750);
DISPLAY 0.617021 (-1075 5750);
PAINT BLUE (-1075 5750);
DISPLAY INVISIBLE (-1075 5750);
FORCEPROP 1 LAST VOLTAGE 6.3V
J 0
(-1075 5900);
DISPLAY 0.617021 (-1075 5900);
PAINT SKYBLUE (-1075 5900);
FORCEPROP 1 LAST TOLERANCE 20%
J 0
(-1075 5950);
DISPLAY 0.617021 (-1075 5950);
PAINT SKYBLUE (-1075 5950);
FORCEPROP 1 LAST VALUE 220UF
J 0
(-1075 6000);
DISPLAY 0.617021 (-1075 6000);
PAINT SKYBLUE (-1075 6000);
FORCEPROP 1 LAST PACK_TYPE SMLF
J 0
(-1075 5800);
DISPLAY 0.617021 (-1075 5800);
PAINT SKYBLUE (-1075 5800);
FORCEPROP 1 LAST MATERIAL ALUM
J 0
(-1075 5850);
DISPLAY 0.617021 (-1075 5850);
PAINT SKYBLUE (-1075 5850);
FORCEPROP 1 LAST LOCATION PC1845
J 0
(-1075 6050);
DISPLAY 0.617021 (-1075 6050);
PAINT AQUA (-1075 6050);
FORCEPROP 1 LASTPIN (-1125 6050) $PN 1
J 0
(-1115 6035);
DISPLAY 0.617021 (-1115 6035);
PAINT MONO (-1115 6035);
FORCEPROP 1 LASTPIN (-1125 5850) $PN 2
J 0
(-1115 5835);
DISPLAY 0.617021 (-1115 5835);
PAINT MONO (-1115 5835);
FORCEPROP 2 LAST CDS_LIB pure_quanta
J 0
(-1125 5950);
DISPLAY INVISIBLE (-1125 5950);
FORCEPROP 1 LAST PATH I32
J 0
(-1075 6100);
DISPLAY 0.978723 (-1075 6100);
DISPLAY INVISIBLE (-1075 6100);
FORCEPROP 0 LAST $SEC 1
J 0
(-1075 6100);
DISPLAY 0.680851 (-1075 6100);
PAINT MONO (-1075 6100);
DISPLAY INVISIBLE (-1075 6100);
FORCEPROP 0 LAST CDS_SEC 1
J 0
(-1075 6100);
DISPLAY 0.680851 (-1075 6100);
DISPLAY INVISIBLE (-1075 6100);
FORCEADD Q_CAP..1
(-675 5950);
FORCEPROP 1 LAST PART_NUMBER CH6222MEA01
J 0
(-625 5800);
DISPLAY 0.617021 (-625 5800);
PAINT BLUE (-625 5800);
DISPLAY INVISIBLE (-625 5800);
FORCEPROP 1 LAST MATERIAL X6S
J 0
(-625 5850);
DISPLAY 0.617021 (-625 5850);
PAINT SKYBLUE (-625 5850);
FORCEPROP 1 LAST VOLTAGE 10V
J 0
(-625 5950);
DISPLAY 0.617021 (-625 5950);
PAINT SKYBLUE (-625 5950);
FORCEPROP 1 LAST TOLERANCE 20%
J 0
(-625 5900);
DISPLAY 0.617021 (-625 5900);
PAINT SKYBLUE (-625 5900);
FORCEPROP 1 LAST PACK_TYPE C0805
J 0
(-625 5750);
DISPLAY 0.617021 (-625 5750);
PAINT SKYBLUE (-625 5750);
FORCEPROP 1 LAST VALUE 22UF
J 0
(-625 6000);
DISPLAY 0.617021 (-625 6000);
PAINT SKYBLUE (-625 6000);
FORCEPROP 1 LAST LOCATION PC1855
J 0
(-625 6050);
DISPLAY 0.617021 (-625 6050);
PAINT AQUA (-625 6050);
FORCEPROP 1 LASTPIN (-675 6050) $PN 1
J 0
(-665 6030);
DISPLAY 0.617021 (-665 6030);
PAINT MONO (-665 6030);
FORCEPROP 1 LASTPIN (-675 5850) $PN 2
J 0
(-665 5830);
DISPLAY 0.617021 (-665 5830);
PAINT MONO (-665 5830);
FORCEPROP 2 LAST CDS_LIB pure_quanta
J 0
(-675 5950);
DISPLAY INVISIBLE (-675 5950);
FORCEPROP 1 LAST PATH I33
J 0
(-625 6100);
DISPLAY 0.978723 (-625 6100);
PAINT WHITE (-625 6100);
DISPLAY INVISIBLE (-625 6100);
FORCEPROP 0 LAST $SEC 1
J 0
(-625 6100);
DISPLAY 0.680851 (-625 6100);
PAINT MONO (-625 6100);
DISPLAY INVISIBLE (-625 6100);
FORCEPROP 0 LAST CDS_SEC 1
J 0
(-625 6100);
DISPLAY 0.680851 (-625 6100);
DISPLAY INVISIBLE (-625 6100);
FORCEADD Q_CAP..1
(-175 5950);
FORCEPROP 1 LAST PART_NUMBER CH6222MEA01
J 0
(-125 5800);
DISPLAY 0.617021 (-125 5800);
PAINT BLUE (-125 5800);
DISPLAY INVISIBLE (-125 5800);
FORCEPROP 1 LAST TOLERANCE 20%
J 0
(-125 5900);
DISPLAY 0.617021 (-125 5900);
PAINT SKYBLUE (-125 5900);
FORCEPROP 1 LAST VOLTAGE 10V
J 0
(-125 5950);
DISPLAY 0.617021 (-125 5950);
PAINT SKYBLUE (-125 5950);
FORCEPROP 1 LAST VALUE 22UF
J 0
(-125 6000);
DISPLAY 0.617021 (-125 6000);
PAINT SKYBLUE (-125 6000);
FORCEPROP 1 LAST PACK_TYPE C0805
J 0
(-125 5750);
DISPLAY 0.617021 (-125 5750);
PAINT SKYBLUE (-125 5750);
FORCEPROP 1 LAST MATERIAL X6S
J 0
(-125 5850);
DISPLAY 0.617021 (-125 5850);
PAINT SKYBLUE (-125 5850);
FORCEPROP 1 LAST LOCATION PC1856
J 0
(-125 6050);
DISPLAY 0.617021 (-125 6050);
PAINT AQUA (-125 6050);
FORCEPROP 1 LASTPIN (-175 6050) $PN 1
J 0
(-165 6030);
DISPLAY 0.617021 (-165 6030);
PAINT MONO (-165 6030);
FORCEPROP 1 LASTPIN (-175 5850) $PN 2
J 0
(-165 5830);
DISPLAY 0.617021 (-165 5830);
PAINT MONO (-165 5830);
FORCEPROP 2 LAST CDS_LIB pure_quanta
J 0
(-175 5950);
DISPLAY INVISIBLE (-175 5950);
FORCEPROP 1 LAST PATH I34
J 0
(-125 6100);
DISPLAY 0.978723 (-125 6100);
PAINT WHITE (-125 6100);
DISPLAY INVISIBLE (-125 6100);
FORCEPROP 0 LAST $SEC 1
J 0
(-125 6100);
DISPLAY 0.680851 (-125 6100);
PAINT MONO (-125 6100);
DISPLAY INVISIBLE (-125 6100);
FORCEPROP 0 LAST CDS_SEC 1
J 0
(-125 6100);
DISPLAY 0.680851 (-125 6100);
DISPLAY INVISIBLE (-125 6100);
FORCEADD GND..1
(250 5550);
FORCEPROP 3 LASTPIN (250 5600) SIG_NAME GND\g
J 0
(260 5610);
DISPLAY 0.659574 (260 5610);
PAINT MONO (260 5610);
DISPLAY INVISIBLE (260 5610);
FORCEPROP 1 LAST HDL_POWER GND
J 0
(250 5700);
DISPLAY 0.872340 (250 5700);
PAINT GREEN (250 5700);
DISPLAY INVISIBLE (250 5700);
FORCEPROP 1 LAST SIZE 1B
J 0
(325 5500);
DISPLAY 0.872340 (325 5500);
PAINT AQUA (325 5500);
DISPLAY INVISIBLE (325 5500);
FORCEPROP 2 LAST CDS_LIB logical_power
J 0
(250 5550);
DISPLAY INVISIBLE (250 5550);
FORCEPROP 1 LAST PATH I35
J 0
(325 5550);
DISPLAY 0.872340 (325 5550);
PAINT AQUA (325 5550);
DISPLAY INVISIBLE (325 5550);
FORCEADD Q_CAP..1
(250 5950);
FORCEPROP 1 LAST PART_NUMBER CH4104K1B00
J 0
(300 5800);
DISPLAY 0.617021 (300 5800);
PAINT BLUE (300 5800);
DISPLAY INVISIBLE (300 5800);
FORCEPROP 1 LAST VOLTAGE 25V
J 0
(300 5950);
DISPLAY 0.617021 (300 5950);
PAINT SKYBLUE (300 5950);
FORCEPROP 1 LAST VALUE 0.1UF
J 0
(300 6000);
DISPLAY 0.617021 (300 6000);
PAINT SKYBLUE (300 6000);
FORCEPROP 1 LAST TOLERANCE 10%
J 0
(300 5900);
DISPLAY 0.617021 (300 5900);
PAINT SKYBLUE (300 5900);
FORCEPROP 1 LAST MATERIAL X7R
J 0
(300 5850);
DISPLAY 0.617021 (300 5850);
PAINT SKYBLUE (300 5850);
FORCEPROP 1 LAST PACK_TYPE 0402
J 0
(300 5750);
DISPLAY 0.617021 (300 5750);
PAINT SKYBLUE (300 5750);
FORCEPROP 1 LAST LOCATION PC1852
J 0
(300 6050);
DISPLAY 0.617021 (300 6050);
PAINT AQUA (300 6050);
FORCEPROP 1 LASTPIN (250 6050) $PN 1
J 0
(260 6030);
DISPLAY 0.617021 (260 6030);
FORCEPROP 1 LASTPIN (250 5850) $PN 2
J 0
(260 5830);
DISPLAY 0.617021 (260 5830);
FORCEPROP 2 LAST SEC_TYPE 0402
J 0
(300 6146);
DISPLAY 1.021277 (300 6146);
DISPLAY INVISIBLE (300 6146);
FORCEPROP 2 LAST CDS_LIB pure_quanta
J 0
(250 5950);
PAINT MONO (250 5950);
DISPLAY INVISIBLE (250 5950);
FORCEPROP 1 LAST PATH I36
J 0
(300 6100);
DISPLAY 0.978723 (300 6100);
PAINT WHITE (300 6100);
DISPLAY INVISIBLE (300 6100);
FORCEPROP 2 LAST SEC 1
J 0
(302 6157);
DISPLAY 0.680851 (302 6157);
PAINT MONO (302 6157);
DISPLAY INVISIBLE (302 6157);
FORCEADD UNIVERSAL_POWER..1
(-3300 7375);
FORCEPROP 1 LAST HDL_POWER P5V_AUX_VCC
J 1
(-3300 7425);
DISPLAY 0.617021 (-3300 7425);
PAINT GREEN (-3300 7425);
FORCEPROP 2 LAST CDS_LIB logical_power
J 0
(-3300 7375);
DISPLAY INVISIBLE (-3300 7375);
FORCEPROP 1 LAST PATH I37
J 0
(-3250 7400);
DISPLAY 0.872340 (-3250 7400);
PAINT AQUA (-3250 7400);
DISPLAY INVISIBLE (-3250 7400);
FORCEADD P1V0..1
(750 6675);
FORCEPROP 3 LASTPIN (750 6625) SIG_NAME P5V_AUX\g
J 0
(760 6635);
DISPLAY 0.659574 (760 6635);
PAINT MONO (760 6635);
DISPLAY INVISIBLE (760 6635);
FORCEPROP 1 LAST HDL_POWER P5V_AUX
J 1
(750 6725);
DISPLAY 0.617021 (750 6725);
PAINT GREEN (750 6725);
FORCEPROP 2 LAST CDS_LIB logical_power
J 0
(750 6675);
PAINT MONO (750 6675);
DISPLAY INVISIBLE (750 6675);
FORCEPROP 1 LAST PATH I38
J 0
(800 6700);
DISPLAY 0.872340 (800 6700);
PAINT AQUA (800 6700);
DISPLAY INVISIBLE (800 6700);
FORCEADD Q_RES..1
(-1875 5400);
FORCEPROP 1 LAST PART_NUMBER CS38872FB18
J 0
(-1775 5350);
DISPLAY 0.617021 (-1775 5350);
PAINT BLUE (-1775 5350);
DISPLAY INVISIBLE (-1775 5350);
FORCEPROP 1 LAST VALUE 88.7K
J 2
(-1550 5450);
DISPLAY 0.617021 (-1550 5450);
PAINT SKYBLUE (-1550 5450);
FORCEPROP 1 LAST MATERIAL CHIP
J 0
(-2175 5300);
DISPLAY 0.617021 (-2175 5300);
PAINT SKYBLUE (-2175 5300);
FORCEPROP 1 LAST TOLERANCE 1%
J 0
(-1775 5300);
DISPLAY 0.638298 (-1775 5300);
PAINT SKYBLUE (-1775 5300);
FORCEPROP 1 LAST PACK_TYPE 0402LF
J 0
(-2188 5336);
DISPLAY 0.617021 (-2188 5336);
PAINT SKYBLUE (-2188 5336);
FORCEPROP 1 LAST LOCATION PR92
J 0
(-2253 5429);
DISPLAY 0.617021 (-2253 5429);
PAINT AQUA (-2253 5429);
FORCEPROP 1 LASTPIN (-1975 5400) $PN 1
J 0
(-1963 5412);
DISPLAY 0.787234 (-1963 5412);
PAINT MONO (-1963 5412);
FORCEPROP 1 LASTPIN (-1775 5400) $PN 2
J 0
(-1813 5412);
DISPLAY 0.787234 (-1813 5412);
PAINT MONO (-1813 5412);
FORCEPROP 1 LAST WATTAGE 1/16W
J 2
(-1301 5418);
DISPLAY 0.978723 (-1301 5418);
PAINT SKYBLUE (-1301 5418);
DISPLAY INVISIBLE (-1301 5418);
FORCEPROP 1 LAST PATH I39
J 0
(-1925 5550);
DISPLAY 0.978723 (-1925 5550);
PAINT WHITE (-1925 5550);
DISPLAY INVISIBLE (-1925 5550);
FORCEPROP 2 LAST CDS_LIB pure_quanta
J 0
(-1875 5400);
DISPLAY INVISIBLE (-1875 5400);
FORCEPROP 0 LAST $SEC 1
J 0
(-1550 5500);
DISPLAY 0.680851 (-1550 5500);
PAINT MONO (-1550 5500);
DISPLAY INVISIBLE (-1550 5500);
FORCEPROP 0 LAST CDS_SEC 1
J 0
(-1550 5500);
DISPLAY 1.021277 (-1550 5500);
DISPLAY INVISIBLE (-1550 5500);
FORCEADD GND..1
(-6400 5100);
FORCEPROP 3 LASTPIN (-6400 5150) SIG_NAME GND\g
J 0
(-6390 5160);
DISPLAY 0.659574 (-6390 5160);
PAINT MONO (-6390 5160);
DISPLAY INVISIBLE (-6390 5160);
FORCEPROP 1 LAST HDL_POWER GND
J 0
(-6400 5250);
DISPLAY 0.872340 (-6400 5250);
PAINT GREEN (-6400 5250);
DISPLAY INVISIBLE (-6400 5250);
FORCEPROP 2 LAST CDS_LIB logical_power
J 0
(-6400 5100);
DISPLAY INVISIBLE (-6400 5100);
FORCEPROP 1 LAST SIZE 1B
J 0
(-6325 5050);
DISPLAY 0.872340 (-6325 5050);
PAINT AQUA (-6325 5050);
DISPLAY INVISIBLE (-6325 5050);
FORCEPROP 1 LAST PATH I4
J 0
(-6325 5100);
DISPLAY 0.872340 (-6325 5100);
PAINT AQUA (-6325 5100);
DISPLAY INVISIBLE (-6325 5100);
FORCEADD Q_INDUCTOR..1
(-7475 7000);
FORCEPROP 1 LAST PART_NUMBER CX220TN1001
J 0
(-7600 7110);
DISPLAY 0.617021 (-7600 7110);
PAINT BLUE (-7600 7110);
DISPLAY INVISIBLE (-7600 7110);
FORCEPROP 2 LAST PACK_TYPE SMLF
J 0
(-7600 7250);
DISPLAY 0.617021 (-7600 7250);
PAINT SKYBLUE (-7600 7250);
FORCEPROP 1 LAST MATERIAL IND
J 0
(-7600 7055);
DISPLAY 0.617021 (-7600 7055);
PAINT SKYBLUE (-7600 7055);
FORCEPROP 2 LAST VALUE BLM18SN220TN1D/8000MA
J 0
(-7600 7200);
DISPLAY 0.617021 (-7600 7200);
PAINT SKYBLUE (-7600 7200);
FORCEPROP 1 LAST LOCATION PL64
J 0
(-7600 7160);
DISPLAY 0.617021 (-7600 7160);
PAINT AQUA (-7600 7160);
FORCEPROP 0 LASTPIN (-7575 6975) $PN 1
J 2
(-7585 6985);
DISPLAY 0.617021 (-7585 6985);
PAINT MONO (-7585 6985);
FORCEPROP 0 LASTPIN (-7375 6975) $PN 2
J 0
(-7365 6985);
DISPLAY 0.617021 (-7365 6985);
PAINT MONO (-7365 6985);
FORCEPROP 2 LAST CDS_LIB pure_quanta
J 0
(-7475 7000);
DISPLAY INVISIBLE (-7475 7000);
FORCEPROP 1 LAST NEEDS_NO_SIZE TRUE
J 0
(-7475 7000);
DISPLAY 0.468085 (-7475 7000);
PAINT GREEN (-7475 7000);
DISPLAY INVISIBLE (-7475 7000);
FORCEPROP 1 LAST PATH I5
J 0
(-7400 7055);
DISPLAY 0.723404 (-7400 7055);
PAINT GREEN (-7400 7055);
DISPLAY INVISIBLE (-7400 7055);
FORCEPROP 0 LAST $SEC 1
J 0
(-7600 7300);
DISPLAY 0.680851 (-7600 7300);
PAINT MONO (-7600 7300);
DISPLAY INVISIBLE (-7600 7300);
FORCEPROP 0 LAST CDS_SEC 1
J 0
(-7600 7300);
DISPLAY 0.680851 (-7600 7300);
DISPLAY INVISIBLE (-7600 7300);
FORCEADD GND..1
(-6975 6375);
FORCEPROP 3 LASTPIN (-6975 6425) SIG_NAME GND\g
J 0
(-6965 6435);
DISPLAY 0.659574 (-6965 6435);
PAINT MONO (-6965 6435);
DISPLAY INVISIBLE (-6965 6435);
FORCEPROP 1 LAST HDL_POWER GND
J 0
(-6975 6525);
DISPLAY 0.872340 (-6975 6525);
PAINT GREEN (-6975 6525);
DISPLAY INVISIBLE (-6975 6525);
FORCEPROP 1 LAST SIZE 1B
J 0
(-6900 6325);
DISPLAY 0.872340 (-6900 6325);
PAINT AQUA (-6900 6325);
DISPLAY INVISIBLE (-6900 6325);
FORCEPROP 2 LAST CDS_LIB logical_power
J 0
(-6975 6375);
DISPLAY INVISIBLE (-6975 6375);
FORCEPROP 1 LAST PATH I6
J 0
(-6900 6375);
DISPLAY 0.872340 (-6900 6375);
PAINT AQUA (-6900 6375);
DISPLAY INVISIBLE (-6900 6375);
FORCEADD Q_CAP..1
(-6975 6750);
FORCEPROP 1 LAST PART_NUMBER CH6223MEA01
J 0
(-6925 6600);
DISPLAY 0.617021 (-6925 6600);
PAINT BLUE (-6925 6600);
DISPLAY INVISIBLE (-6925 6600);
FORCEPROP 1 LAST VOLTAGE 16V
J 0
(-6925 6750);
DISPLAY 0.617021 (-6925 6750);
PAINT SKYBLUE (-6925 6750);
FORCEPROP 1 LAST TOLERANCE 20%
J 0
(-6925 6700);
DISPLAY 0.617021 (-6925 6700);
PAINT SKYBLUE (-6925 6700);
FORCEPROP 1 LAST PACK_TYPE C0805
J 0
(-6925 6550);
DISPLAY 0.617021 (-6925 6550);
PAINT SKYBLUE (-6925 6550);
FORCEPROP 1 LAST MATERIAL X6S
J 0
(-6925 6650);
DISPLAY 0.617021 (-6925 6650);
PAINT SKYBLUE (-6925 6650);
FORCEPROP 1 LAST VALUE 22UF
J 0
(-6925 6800);
DISPLAY 0.617021 (-6925 6800);
PAINT SKYBLUE (-6925 6800);
FORCEPROP 1 LAST LOCATION PC1849
J 0
(-6925 6850);
DISPLAY 0.617021 (-6925 6850);
PAINT AQUA (-6925 6850);
FORCEPROP 1 LASTPIN (-6975 6850) $PN 1
J 0
(-6965 6830);
DISPLAY 0.617021 (-6965 6830);
PAINT MONO (-6965 6830);
FORCEPROP 1 LASTPIN (-6975 6650) $PN 2
J 0
(-6965 6630);
DISPLAY 0.617021 (-6965 6630);
PAINT MONO (-6965 6630);
FORCEPROP 2 LAST CDS_LIB pure_quanta
J 0
(-6975 6750);
DISPLAY INVISIBLE (-6975 6750);
FORCEPROP 1 LAST PATH I7
J 0
(-6925 6900);
DISPLAY 0.978723 (-6925 6900);
PAINT WHITE (-6925 6900);
DISPLAY INVISIBLE (-6925 6900);
FORCEPROP 0 LAST $SEC 1
J 0
(-6925 6900);
DISPLAY 0.680851 (-6925 6900);
PAINT MONO (-6925 6900);
DISPLAY INVISIBLE (-6925 6900);
FORCEPROP 0 LAST CDS_SEC 1
J 0
(-6925 6900);
DISPLAY 1.021277 (-6925 6900);
DISPLAY INVISIBLE (-6925 6900);
FORCEADD Q_CAP..1
R 2
(-6400 5475);
FORCEPROP 1 LAST PART_NUMBER CH5104KEB02
J 0
(-6300 5300);
DISPLAY 0.617021 (-6300 5300);
PAINT BLUE (-6300 5300);
DISPLAY INVISIBLE (-6300 5300);
FORCEPROP 1 LAST PACK_TYPE C0402
J 0
(-6300 5349);
DISPLAY 0.617021 (-6300 5349);
PAINT SKYBLUE (-6300 5349);
FORCEPROP 1 LAST VALUE 1UF
J 0
(-6300 5545);
DISPLAY 0.617021 (-6300 5545);
PAINT SKYBLUE (-6300 5545);
FORCEPROP 1 LAST TOLERANCE 10%
J 0
(-6300 5447);
DISPLAY 0.617021 (-6300 5447);
PAINT SKYBLUE (-6300 5447);
FORCEPROP 1 LAST MATERIAL X6S
J 0
(-6300 5398);
DISPLAY 0.617021 (-6300 5398);
PAINT SKYBLUE (-6300 5398);
FORCEPROP 1 LAST VOLTAGE 25V
J 0
(-6300 5496);
DISPLAY 0.617021 (-6300 5496);
PAINT SKYBLUE (-6300 5496);
FORCEPROP 1 LAST LOCATION PC1848
J 2
(-6175 5600);
DISPLAY 0.617021 (-6175 5600);
PAINT AQUA (-6175 5600);
FORCEPROP 1 LASTPIN (-6400 5575) $PN 1
J 2
(-6354 5546);
DISPLAY 0.617021 (-6354 5546);
FORCEPROP 1 LASTPIN (-6400 5375) $PN 2
J 2
(-6356 5370);
DISPLAY 0.617021 (-6356 5370);
FORCEPROP 2 LAST CDS_LIB pure_quanta
J 0
(-6400 5475);
DISPLAY INVISIBLE (-6400 5475);
FORCEPROP 2 LAST SIGNAL_MODEL DEFAULT_CAPACITOR_100000PF_2_1
R 3
J 1
(-6470 5423);
DISPLAY 0.744681 (-6470 5423);
PAINT MONO (-6470 5423);
DISPLAY INVISIBLE (-6470 5423);
FORCEPROP 2 LAST SEC_TYPE C0402
J 0
(-6450 5671);
DISPLAY 1.021277 (-6450 5671);
DISPLAY INVISIBLE (-6450 5671);
FORCEPROP 1 LAST PATH I8
J 2
(-6450 5625);
DISPLAY 0.978723 (-6450 5625);
PAINT WHITE (-6450 5625);
DISPLAY INVISIBLE (-6450 5625);
FORCEPROP 2 LAST SEC 1
J 0
(-6450 5671);
DISPLAY 0.680851 (-6450 5671);
PAINT MONO (-6450 5671);
DISPLAY INVISIBLE (-6450 5671);
FORCEADD UNIVERSAL_POWER..1
(-6400 5975);
FORCEPROP 3 LASTPIN (-6400 5925) SIG_NAME P5V_AUX_VCC\g
J 0
(-6390 5935);
DISPLAY 0.659574 (-6390 5935);
PAINT MONO (-6390 5935);
DISPLAY INVISIBLE (-6390 5935);
FORCEPROP 1 LAST HDL_POWER P5V_AUX_VCC
J 1
(-6400 6025);
DISPLAY 0.617021 (-6400 6025);
PAINT GREEN (-6400 6025);
FORCEPROP 2 LAST CDS_LIB logical_power
J 0
(-6400 5975);
PAINT MONO (-6400 5975);
DISPLAY INVISIBLE (-6400 5975);
FORCEPROP 1 LAST PATH I9
J 0
(-6350 6000);
DISPLAY 0.872340 (-6350 6000);
PAINT AQUA (-6350 6000);
DISPLAY INVISIBLE (-6350 6000);
FORCEADD QUANTA_TITLE_BLOCK_C..1
(1250 3025);
FORCEPROP 0 LAST CDS_CON_LAST_MODIFIED Fri Aug 25 14:04:29 2023
J 0
(-635 3040);
DISPLAY INVISIBLE (-635 3040);
FORCEPROP 1 LAST CUSTOM_TXT_CDS <CON_LAST_MODIFIED>
J 0
(-635 3040);
DISPLAY 0.978723 (-635 3040);
FORCEPROP 2 LAST CUSTOM_TXT_CDS <XR_PAGE_TITLE>
J 0
(-6640 8275);
DISPLAY 0.638298 (-6640 8275);
PAINT PINK (-6640 8275);
DISPLAY INVISIBLE (-6640 8275);
FORCEPROP 1 LAST CUSTOM_TXT_CDS <NAME_2>
J 0
(-1925 3075);
FORCEPROP 1 LAST CUSTOM_TXT_CDS <NAME_1>
J 0
(-1925 3200);
FORCEPROP 1 LAST CUSTOM_TXT_CDS <Q_NUMBER>
J 0
(-153 3128);
DISPLAY 1.212766 (-153 3128);
FORCEPROP 1 LAST CUSTOM_TXT_CDS <Q_PROJ>
J 0
(-1132 3127);
DISPLAY 1.212766 (-1132 3127);
FORCEPROP 1 LAST CUSTOM_TXT_CDS <Q_REV>
J 0
(1066 3128);
DISPLAY 1.212766 (1066 3128);
FORCEPROP 1 LAST CUSTOM_TXT_CDS <CON_PAGE_NUM> OF <CON_TOTAL_PAGES>
J 0
(804 3043);
DISPLAY 0.978723 (804 3043);
FORCEPROP 1 LAST Q_TITLE MPQ8633A/P5V_AUX
J 0
(-8025 3075);
DISPLAY 2.446809 (-8025 3075);
PAINT GREEN (-8025 3075);
FORCEPROP 1 LAST Q_DEPT 
J 1
(-2513 3074);
DISPLAY 1.957447 (-2513 3074);
PAINT GREEN (-2513 3074);
FORCEPROP 2 LAST CDS_XR_PAGE_TITLE CR-258 : @S9S_MB_2U_LIB.S9S_MB_2U(SCH_1):PAGE258
J 0
(-6640 8275);
DISPLAY 0.638298 (-6640 8275);
PAINT PINK (-6640 8275);
DISPLAY INVISIBLE (-6640 8275);
FORCEPROP 2 LAST PAGE_BORDER TRUE
J 0
(-6640 8275);
DISPLAY 0.638298 (-6640 8275);
PAINT PINK (-6640 8275);
DISPLAY INVISIBLE (-6640 8275);
FORCEPROP 1 LAST CDS_LMAN_SYM_OUTLINE -9475,6775,100,-125
J 0
(1250 3025);
DISPLAY 0.468085 (1250 3025);
PAINT GREEN (1250 3025);
DISPLAY INVISIBLE (1250 3025);
FORCEPROP 2 LAST CDS_LIB pure_quanta
J 0
(1250 3025);
DISPLAY INVISIBLE (1250 3025);
FORCEPROP 1 LAST COMMENT_BODY TRUE
J 0
(1262 3012);
DISPLAY 0.978723 (1262 3012);
PAINT GREEN (1262 3012);
DISPLAY INVISIBLE (1262 3012);
WIRE 16 -1 (-7746 7145)(-7746 6975);
WIRE 16 -1 (-6400 5925)(-6400 5750);
WIRE 16 -1 (-3300 7325)(-3300 7175);
FORCEPROP 2 LAST SIG_NAME P5V_AUX_VCC\G
J 0
(-3290 7335);
DISPLAY 0.659574 (-3290 7335);
DISPLAY INVISIBLE (-3290 7335);
WIRE 16 -1 (750 6200)(750 6625);
WIRE 16 -1 (750 6200)(750 5400);
WIRE 16 -1 (750 6200)(250 6200);
WIRE 16 -1 (-7750 6575)(-7750 6675);
WIRE 16 -1 (-6400 5150)(-6400 5375);
WIRE 16 -1 (-6975 6425)(-6975 6528);
WIRE 16 -1 (-5462 4943)(-5462 5082);
WIRE 16 -1 (-3950 5125)(-3950 5350);
WIRE 16 -1 (-3825 5125)(-3825 5200);
WIRE 16 -1 (-5150 5900)(-5150 5875);
WIRE 16 -1 (-5450 5900)(-5150 5900);
WIRE 16 -1 (-3400 5200)(-3400 5600);
WIRE 16 -1 (-3250 5375)(-3250 5200);
WIRE 16 -1 (250 5600)(250 5700);
WIRE 16 -1 (-3300 6450)(-3300 6500);
WIRE 16 -1 (-4175 6500)(-3300 6500);
FORCEPROP 2 LAST SIG_NAME SW_P5V_AUX_BST
J 0
(-4085 6510);
DISPLAY 0.617021 (-4085 6510);
WIRE 16 -1 (-3300 6250)(-3300 6200);
WIRE 16 -1 (-3300 6200)(-2500 6200);
WIRE 16 -1 (-4175 6200)(-3300 6200);
FORCEPROP 2 LAST SIG_NAME SW_P5V_AUX_SW
J 0
(-4085 6210);
DISPLAY 0.617021 (-4085 6210);
WIRE 16 -1 (-4175 5750)(-3250 5750);
FORCEPROP 2 LAST SIG_NAME P5V_AUX_FB
J 0
(-4085 5760);
DISPLAY 0.617021 (-4085 5760);
WIRE 16 -1 (-3250 5575)(-3250 5750);
WIRE 16 -1 (-2500 5750)(-3250 5750);
WIRE 16 -1 (-2500 5750)(-2500 5400);
WIRE 16 -1 (-1975 5400)(-2500 5400);
WIRE 16 -1 (-2500 5400)(-2500 5075);
WIRE 16 -1 (-2000 5075)(-2500 5075);
WIRE 16 -1 (-2300 6200)(-1125 6200);
WIRE 16 -1 (-1125 6050)(-1125 6200);
WIRE 16 -1 (-675 6200)(-675 6050);
WIRE 16 -1 (-1125 6200)(-675 6200);
WIRE 16 -1 (-175 6200)(-175 6050);
WIRE 16 -1 (-175 6200)(-675 6200);
WIRE 16 -1 (250 6200)(-175 6200);
WIRE 16 -1 (250 6050)(250 6200);
WIRE 16 -1 (-1775 5400)(-950 5400);
WIRE 16 -1 (750 5400)(-950 5400);
WIRE 16 -1 (-950 5075)(-1800 5075);
WIRE 16 -1 (-950 5075)(-950 5400);
WIRE 16 -1 (-5150 6650)(-4975 6650);
WIRE 16 -1 (-5150 6700)(-5150 6650);
WIRE 16 -1 (-5150 6700)(-4975 6700);
WIRE 16 -1 (-5150 6975)(-5150 6700);
WIRE 16 -1 (-5725 6850)(-5725 6975);
WIRE 16 -1 (-5725 6975)(-5150 6975);
WIRE 16 -1 (-6125 6850)(-6125 6975);
WIRE 16 -1 (-6125 6975)(-5725 6975);
WIRE 16 -1 (-6575 6850)(-6575 6975);
WIRE 16 -1 (-6575 6975)(-6125 6975);
WIRE 16 -1 (-6975 6850)(-6975 6975);
WIRE 16 -1 (-6975 6975)(-6575 6975);
FORCEPROP 2 LAST SIG_NAME SW_P5V_AUX_FLT
J 0
(-5585 6985);
DISPLAY 0.617021 (-5585 6985);
WIRE 16 -1 (-7375 6975)(-6975 6975);
WIRE 16 -1 (-6400 5750)(-4975 5750);
WIRE 16 -1 (-6400 5575)(-6400 5750);
WIRE 16 -1 (-3400 5600)(-4175 5600);
WIRE 16 3135 (-325 8975)(950 8975);
WIRE 16 3135 (950 8975)(950 8375);
WIRE 16 3135 (-325 8375)(-325 8975);
WIRE 16 3135 (-325 8375)(950 8375);
WIRE 16 -1 (250 5850)(250 5700);
WIRE 16 -1 (-175 5850)(-175 5700);
WIRE 16 -1 (250 5700)(-175 5700);
WIRE 16 -1 (-675 5850)(-675 5700);
WIRE 16 -1 (-175 5700)(-675 5700);
WIRE 16 -1 (-675 5700)(-1125 5700);
WIRE 16 -1 (-1125 5850)(-1125 5700);
WIRE 16 -1 (-619 5576)(-619 5577);
WIRE 16 -1 (-1700 6700)(-2625 6700);
FORCEPROP 2 LAST SIG_NAME PWRGD_P5V_AUX
J 0
(-2235 6710);
DISPLAY 0.617021 (-2235 6710);
WIRE 16 -1 (-2332 4872)(-2332 4873);
WIRE 16 -1 (-3300 6700)(-4175 6700);
FORCEPROP 2 LAST SIG_NAME PWRGD_P5V_AUX_R
J 0
(-4085 6710);
DISPLAY 0.617021 (-4085 6710);
WIRE 16 -1 (-3300 6975)(-3300 6700);
WIRE 16 -1 (-2825 6700)(-3300 6700);
WIRE 16 -1 (-3950 5400)(-4175 5400);
WIRE 16 -1 (-4175 5350)(-3950 5350);
WIRE 16 -1 (-3950 5350)(-3950 5400);
WIRE 16 -1 (-3825 5500)(-3825 5400);
WIRE 16 -1 (-4175 5500)(-3825 5500);
FORCEPROP 2 LAST SIG_NAME P5V_AUX_REF
J 0
(-4085 5510);
DISPLAY 0.617021 (-4085 5510);
WIRE 16 -1 (-5462 5400)(-4975 5400);
WIRE 16 -1 (-5462 5282)(-5462 5400);
FORCEPROP 2 LAST SIG_NAME P5V_AUX_CS
J 0
(-5585 5410);
DISPLAY 0.617021 (-5585 5410);
WIRE 16 -1 (-5725 6200)(-4975 6200);
FORCEPROP 2 LAST SIG_NAME PWRGD_P3V3_AUX
J 0
(-5585 6210);
DISPLAY 0.617021 (-5585 6210);
WIRE 16 -1 (-5725 6650)(-5725 6528);
WIRE 16 -1 (-6125 6650)(-6125 6528);
WIRE 16 -1 (-5725 6528)(-6125 6528);
WIRE 16 -1 (-6575 6650)(-6575 6528);
WIRE 16 -1 (-6125 6528)(-6575 6528);
WIRE 16 -1 (-6975 6528)(-6575 6528);
WIRE 16 -1 (-6975 6650)(-6975 6528);
WIRE 16 -1 (-4975 6000)(-5900 6000);
FORCEPROP 2 LAST SIG_NAME P5V_AUX_MODE
J 0
(-5585 6010);
DISPLAY 0.638298 (-5585 6010);
WIRE 16 -1 (-5900 6000)(-5900 5900);
WIRE 16 -1 (-5900 5900)(-5650 5900);
WIRE 16 2175 (-7900 3500)(-7050 3500);
WIRE 16 2175 (-7050 3900)(-7050 3500);
WIRE 16 2175 (-7900 3900)(-7900 3500);
WIRE 16 2175 (-7900 3900)(-7050 3900);
WIRE 16 -1 (-7750 6875)(-7750 6975);
WIRE 16 -1 (-7750 6975)(-7746 6975);
WIRE 16 -1 (-7575 6975)(-7746 6975);
DOT 1 (750 6200);
DOT 1 (250 6200);
DOT 1 (-175 6200);
DOT 1 (250 5700);
DOT 1 (-175 5700);
DOT 1 (-675 6200);
DOT 1 (-1125 6200);
DOT 1 (-675 5700);
DOT 1 (-950 5400);
DOT 1 (-2500 5400);
DOT 1 (-3300 6700);
DOT 1 (-3300 6200);
DOT 1 (-3250 5750);
DOT 1 (-3950 5350);
DOT 1 (-5150 6700);
DOT 1 (-5725 6975);
DOT 1 (-6125 6975);
DOT 1 (-6125 6528);
DOT 1 (-6575 6975);
DOT 1 (-6575 6528);
DOT 1 (-6400 5750);
DOT 1 (-6975 6975);
DOT 1 (-6975 6528);
DOT 1 (-7746 6975);
FORCENOTE
PR92 NEED CHANGE TO CS38872FB04 FOR EF PART
(-2475 5575) 0;
DISPLAY LEFT (-2475 5575);
DISPLAY 1.021277 (-2475 5575);
FORCENOTE
DCR=15MOHM
(-2600 5950) 0;
DISPLAY LEFT (-2600 5950);
DISPLAY 1.021277 (-2600 5950);
FORCENOTE
ISAT=13A
(-2600 6000) 0;
DISPLAY LEFT (-2600 6000);
DISPLAY 1.021277 (-2600 6000);
FORCENOTE
10.3*11.2*4.0
(-2600 6050) 0;
DISPLAY LEFT (-2600 6050);
DISPLAY 1.021277 (-2600 6050);
FORCENOTE
20220808 ADD CHANGE LIST
(-7625 4900) 0;
DISPLAY LEFT (-7625 4900);
DISPLAY 1.595745 (-7625 4900);
PAINT PINK (-7625 4900);
FORCENOTE
TRANSIENT TOLERANCE = +/-5.0%
(-300 8700) 0;
DISPLAY LEFT (-300 8700);
DISPLAY 0.808511 (-300 8700);
PAINT WHITE (-300 8700);
FORCENOTE
WORK FREQUENCY = 600KHZ
(-300 8400) 0;
DISPLAY LEFT (-300 8400);
DISPLAY 0.808511 (-300 8400);
PAINT WHITE (-300 8400);
FORCENOTE
DC TOLERANCE = +/-1.5%
(-300 8800) 0;
DISPLAY LEFT (-300 8800);
DISPLAY 0.808511 (-300 8800);
PAINT WHITE (-300 8800);
FORCENOTE
OUTPUT RIPPLE & NOISE = +/-1.0%
(-300 8750) 0;
DISPLAY LEFT (-300 8750);
DISPLAY 0.808511 (-300 8750);
PAINT WHITE (-300 8750);
FORCENOTE
TDC = 1.8A
(-300 8650) 0;
DISPLAY LEFT (-300 8650);
DISPLAY 0.808511 (-300 8650);
PAINT RED (-300 8650);
FORCENOTE
IMAX = 2.1A
(-300 8600) 0;
DISPLAY LEFT (-300 8600);
DISPLAY 0.808511 (-300 8600);
PAINT RED (-300 8600);
FORCENOTE
CURRENT STEP = 1A
(-300 8500) 0;
DISPLAY LEFT (-300 8500);
DISPLAY 0.808511 (-300 8500);
PAINT WHITE (-300 8500);
FORCENOTE
SLEW RATE = 1A/US
(-300 8450) 0;
DISPLAY LEFT (-300 8450);
DISPLAY 0.808511 (-300 8450);
PAINT WHITE (-300 8450);
FORCENOTE
DESIGN SPECIFICATION
(-300 8925) 0;
DISPLAY LEFT (-300 8925);
DISPLAY 0.808511 (-300 8925);
PAINT WHITE (-300 8925);
FORCENOTE
OUTPUT VOLTAGE = 5.0V
(-300 8850) 0;
DISPLAY LEFT (-300 8850);
DISPLAY 0.808511 (-300 8850);
PAINT WHITE (-300 8850);
FORCENOTE
OCP(IMAX*120%) = 4A
(-300 8550) 0;
DISPLAY LEFT (-300 8550);
DISPLAY 0.808511 (-300 8550);
PAINT RED (-300 8550);
FORCENOTE
P5V_AUX
(-5350 8075) 0;
DISPLAY LEFT (-5350 8075);
DISPLAY 4.914894 (-5350 8075);
PAINT YELLOW (-5350 8075);
FORCENOTE
RA
(-1925 5475) 0;
DISPLAY LEFT (-1925 5475);
DISPLAY 1.021277 (-1925 5475);
FORCENOTE
PCMB104E-4R7MS
(-2600 6100) 0;
DISPLAY LEFT (-2600 6100);
DISPLAY 1.021277 (-2600 6100);
FORCENOTE
RB
(-3175 5675) 0;
DISPLAY LEFT (-3175 5675);
DISPLAY 1.021277 (-3175 5675);
FORCENOTE
PC1848 MAIN 1UF
(-6925 4800) 0;
DISPLAY LEFT (-6925 4800);
DISPLAY 1.276596 (-6925 4800);
PAINT PINK (-6925 4800);
FORCENOTE
3RD 1UF
(-6450 4600) 0;
DISPLAY LEFT (-6450 4600);
DISPLAY 1.276596 (-6450 4600);
PAINT PINK (-6450 4600);
FORCENOTE
20220804 CHANGE IC TABLE
(-7875 3400) 0;
DISPLAY LEFT (-7875 3400);
DISPLAY 1.595745 (-7875 3400);
PAINT PINK (-7875 3400);
FORCENOTE
3RD AL008633007
(-7850 3550) 0;
DISPLAY LEFT (-7850 3550);
DISPLAY 1.021277 (-7850 3550);
PAINT WHITE (-7850 3550);
FORCENOTE
2ND AL000548006
(-7850 3625) 0;
DISPLAY LEFT (-7850 3625);
DISPLAY 1.021277 (-7850 3625);
PAINT WHITE (-7850 3625);
FORCENOTE
1ST AL053318002
(-7850 3700) 0;
DISPLAY LEFT (-7850 3700);
DISPLAY 1.021277 (-7850 3700);
PAINT WHITE (-7850 3700);
FORCENOTE
IC TABLE
(-7875 3800) 0;
DISPLAY LEFT (-7875 3800);
DISPLAY 1.170213 (-7875 3800);
PAINT WHITE (-7875 3800);
FORCENOTE
2ND 2.2UF
(-6450 4700) 0;
DISPLAY LEFT (-6450 4700);
DISPLAY 1.276596 (-6450 4700);
PAINT PINK (-6450 4700);
FORCENOTE
PC1877 MAIN 47PF
(-2300 4175) 0;
DISPLAY LEFT (-2300 4175);
DISPLAY 1.276596 (-2300 4175);
PAINT PINK (-2300 4175);
FORCENOTE
20220808 ADD CHANGE LIST
(-3000 4275) 0;
DISPLAY LEFT (-3000 4275);
DISPLAY 1.595745 (-3000 4275);
PAINT PINK (-3000 4275);
FORCENOTE
VOUT=0.6(1+RA/RB)=5.11V
(-3045 4551) 0;
DISPLAY LEFT (-3045 4551);
DISPLAY 2.000000 (-3045 4551);
PAINT SKYBLUE (-3045 4551);
FORCENOTE
2ND 270PF
(-1825 4075) 0;
DISPLAY LEFT (-1825 4075);
DISPLAY 1.276596 (-1825 4075);
PAINT PINK (-1825 4075);
FORCENOTE
3RD 47PF
(-1825 3975) 0;
DISPLAY LEFT (-1825 3975);
DISPLAY 1.276596 (-1825 3975);
PAINT PINK (-1825 3975);
QUIT
